FILE_TYPE = MULTI_PHYS_TABLE;
PART 'ADM1085'
{===============================================================================================================================================================================================================}
:PACK_TYPE | MATERIAL | PART_NUMBER     = EnvComp | PART_NUMBER  | JEDEC_TYPE        | DESCRIPTION                     | CLASS | COMPONENT_TYPE | HEIGHT     | LPID   | SPEED_URL | Status |RPL| AML | Bus_Unit | Days ;
{===============================================================================================================================================================================================================}
'SMT'      | 'IC'     | 'H46130-001'(!) = 'UNK;UNK;UNK;UNK;ok;CIP' | 'H46130-001' | 'SSOP6_53_65MC'   |'IC,LIN,SPRVSR,6SC70,ADM1085,AH' | 'IC'  | 'SMALLSMT'     | '0.043 IN' |'3211' | 'http://speed.intel.com:8081/speed/module/pdm/item/pdm_item_detail_direct.asp?item_cde=H46130-001&item_rev=01&url_param=unused' | 'Design' | 'NO' | '1' | 'APD' | '???' 
'SMT'      | 'EMPTY'  | 'H46130-001'(!) = 'UNK;UNK;UNK;UNK;ok;CIP' | 'H46130-001' | 'SSOP6_53_65MC'   |'IC,LIN,SPRVSR,6SC70,ADM1085,AH' | 'IO'  | 'SMALLSMT'     | '0.043 IN' |'3211' | 'http://speed.intel.com:8081/speed/module/pdm/item/pdm_item_detail_direct.asp?item_cde=H46130-001&item_rev=01&url_param=unused' | 'Design' | 'NO' | '1' | 'APD' | '???' 
END_PART
END.
